(kicad_pcb
	(version 20260206)
	(generator "pcbnew")
	(generator_version "10.0")
	(general
		(thickness 1.6)
		(legacy_teardrops no)
	)
	(paper "A4")
	(title_block
		(title "03242023_DA0F0TMBIJ0_F0T_Motherboard_J_brd_V01_OCP.brd")
		(comment 1 "Grand Teton / footprints 1814-1819 of 6105")
	)
	(layers
		(0 "F.Cu" signal "TOP")
		(4 "In1.Cu" signal "GND")
		(6 "In2.Cu" signal "IN1")
		(8 "In3.Cu" signal "GND1")
		(10 "In4.Cu" signal "IN2")
		(12 "In5.Cu" signal "GND2")
		(14 "In6.Cu" signal "IN3")
		(16 "In7.Cu" signal "GND3")
		(18 "In8.Cu" signal "VCC")
		(20 "In9.Cu" signal "VCC1")
		(22 "In10.Cu" signal "GND4")
		(24 "In11.Cu" signal "IN4")
		(26 "In12.Cu" signal "GND5")
		(28 "In13.Cu" signal "IN5")
		(30 "In14.Cu" signal "GND6")
		(32 "In15.Cu" signal "IN6")
		(34 "In16.Cu" signal "GND7")
		(2 "B.Cu" signal "BOTTOM")
		(9 "F.Adhes" user "F.Adhesive")
		(11 "B.Adhes" user "B.Adhesive")
		(13 "F.Paste" user "Package Geometry/Pastemask Top")
		(15 "B.Paste" user "Package Geometry/Pastemask Bottom")
		(5 "F.SilkS" user "Ref Des/Silkscreen Top")
		(7 "B.SilkS" user "Ref Des/Silkscreen Bottom")
		(1 "F.Mask" user "Board Geometry/Soldermask Top")
		(3 "B.Mask" user "Board Geometry/Soldermask Bottom")
		(17 "Dwgs.User" user "User.Drawings")
		(19 "Cmts.User" user "User.Comments")
		(21 "Eco1.User" user "User.Eco1")
		(23 "Eco2.User" user "User.Eco2")
		(25 "Edge.Cuts" user "Board Geometry/Outline")
		(27 "Margin" user)
		(31 "F.CrtYd" user "Package Geometry/Place Bound Top")
		(29 "B.CrtYd" user "Package Geometry/Place Bound Bottom")
		(35 "F.Fab" user "Ref Des/Assembly Top")
		(33 "B.Fab" user "Ref Des/Assembly Bottom")
	)
	(footprint ""
		(layer "F.Cu")
		(at 377.637294 -327.79335)
		(property "Reference" "PL10"
			(at 4.840986 4.553712 0)
			(unlocked yes)
			(layer "F.SilkS")
			(effects
				(font
					(size 0.7874 0.5842)
					(thickness 0.1524)
				)
				(justify left)
			)
		)
		(property "Value" ""
			(at 0 0 0)
			(layer "F.Fab")
			(effects
				(font
					(size 1.27 1.27)
				)
			)
		)
		(duplicate_pad_numbers_are_jumpers no)
		(fp_line
			(start -3.750056 -5.500116)
			(end -2.393442 -5.500116)
			(stroke
				(width 0.1524)
				(type default)
			)
			(layer "F.SilkS")
		)
		(fp_line
			(start -3.750056 5.500116)
			(end -3.750056 -5.500116)
			(stroke
				(width 0.1524)
				(type default)
			)
			(layer "F.SilkS")
		)
		(fp_line
			(start -2.393442 5.500116)
			(end -3.750056 5.500116)
			(stroke
				(width 0.1524)
				(type default)
			)
			(layer "F.SilkS")
		)
		(fp_line
			(start 2.393442 5.500116)
			(end 3.750056 5.500116)
			(stroke
				(width 0.1524)
				(type default)
			)
			(layer "F.SilkS")
		)
		(fp_line
			(start 3.750056 -5.500116)
			(end 2.393442 -5.500116)
			(stroke
				(width 0.1524)
				(type default)
			)
			(layer "F.SilkS")
		)
		(fp_line
			(start 3.750056 5.500116)
			(end 3.750056 -5.500116)
			(stroke
				(width 0.1524)
				(type default)
			)
			(layer "F.SilkS")
		)
		(fp_poly
			(pts
				(xy -4.9276 -4.757928) (xy -3.9116 -4.249928) (xy -4.9276 -3.741928)
			)
			(stroke
				(width 0)
				(type default)
			)
			(fill yes)
			(layer "F.SilkS")
		)
		(fp_line
			(start -3.750056 -5.500116)
			(end -3.750056 5.500116)
			(stroke
				(width 0.1)
				(type default)
			)
			(layer "F.Fab")
		)
		(fp_line
			(start -3.750056 5.500116)
			(end 3.750056 5.500116)
			(stroke
				(width 0.1)
				(type default)
			)
			(layer "F.Fab")
		)
		(fp_line
			(start 3.750056 -5.500116)
			(end -3.750056 -5.500116)
			(stroke
				(width 0.1)
				(type default)
			)
			(layer "F.Fab")
		)
		(fp_line
			(start 3.750056 5.500116)
			(end 3.750056 -5.500116)
			(stroke
				(width 0.1)
				(type default)
			)
			(layer "F.Fab")
		)
		(fp_poly
			(pts
				(xy -4.9276 -4.757928) (xy -4.9276 -3.741928) (xy -3.9116 -4.249928)
			)
			(stroke
				(width 0)
				(type default)
			)
			(fill yes)
			(layer "F.Fab")
		)
		(pad "1" smd rect
			(at 0 -4.249928 270)
			(size 2.413 4.5212)
			(layers "F.Cu" "F.Mask" "F.Paste")
			(net "SW_PVCCIN_CPU0_SW5")
		)
		(pad "2" smd rect
			(at 0 -1.175004 270)
			(size 1.3716 4.5212)
			(layers "F.Cu" "F.Mask" "F.Paste")
			(net "IND_P0_CPL5")
		)
		(pad "3" smd rect
			(at 0 1.175004 270)
			(size 1.3716 4.5212)
			(layers "F.Cu" "F.Mask" "F.Paste")
			(net "IND_P0_CPL8")
		)
		(pad "4" smd rect
			(at 0 4.249928 270)
			(size 2.413 4.5212)
			(layers "F.Cu" "F.Mask" "F.Paste")
			(net "PVCCIN_CPU0")
		)
	)
	(footprint ""
		(layer "F.Cu")
		(at 65.60058 -116.488718)
		(property "Reference" "C2056"
			(at 0 0 0)
			(layer "F.SilkS")
			(hide yes)
			(effects
				(font
					(size 1.27 1.27)
				)
			)
		)
		(property "Value" ""
			(at 0 0 0)
			(layer "F.Fab")
			(effects
				(font
					(size 1.27 1.27)
				)
			)
		)
		(duplicate_pad_numbers_are_jumpers no)
		(fp_line
			(start -0.7874 -0.4064)
			(end 0.7874 -0.4064)
			(stroke
				(width 0.1524)
				(type default)
			)
			(layer "F.SilkS")
		)
		(fp_line
			(start -0.7874 0.4064)
			(end -0.7874 -0.4064)
			(stroke
				(width 0.1524)
				(type default)
			)
			(layer "F.SilkS")
		)
		(fp_line
			(start 0.7874 -0.4064)
			(end 0.7874 0.4064)
			(stroke
				(width 0.1524)
				(type default)
			)
			(layer "F.SilkS")
		)
		(fp_line
			(start 0.7874 0.4064)
			(end -0.7874 0.4064)
			(stroke
				(width 0.1524)
				(type default)
			)
			(layer "F.SilkS")
		)
		(fp_line
			(start -0.67945 -0.305054)
			(end -0.12065 -0.305054)
			(stroke
				(width 0.1)
				(type default)
			)
			(layer "F.Fab")
		)
		(fp_line
			(start -0.67945 0.3048)
			(end -0.67945 -0.305054)
			(stroke
				(width 0.1)
				(type default)
			)
			(layer "F.Fab")
		)
		(fp_line
			(start -0.12065 -0.305054)
			(end -0.12065 -0.2794)
			(stroke
				(width 0.1)
				(type default)
			)
			(layer "F.Fab")
		)
		(fp_line
			(start -0.12065 -0.2794)
			(end 0.12065 -0.2794)
			(stroke
				(width 0.1)
				(type default)
			)
			(layer "F.Fab")
		)
		(fp_line
			(start -0.12065 0.2794)
			(end -0.12065 0.3048)
			(stroke
				(width 0.1)
				(type default)
			)
			(layer "F.Fab")
		)
		(fp_line
			(start -0.12065 0.3048)
			(end -0.67945 0.3048)
			(stroke
				(width 0.1)
				(type default)
			)
			(layer "F.Fab")
		)
		(fp_line
			(start 0.120396 0.2794)
			(end -0.12065 0.2794)
			(stroke
				(width 0.1)
				(type default)
			)
			(layer "F.Fab")
		)
		(fp_line
			(start 0.120396 0.3048)
			(end 0.120396 0.2794)
			(stroke
				(width 0.1)
				(type default)
			)
			(layer "F.Fab")
		)
		(fp_line
			(start 0.12065 -0.3048)
			(end 0.67945 -0.3048)
			(stroke
				(width 0.1)
				(type default)
			)
			(layer "F.Fab")
		)
		(fp_line
			(start 0.12065 -0.2794)
			(end 0.12065 -0.3048)
			(stroke
				(width 0.1)
				(type default)
			)
			(layer "F.Fab")
		)
		(fp_line
			(start 0.67945 -0.3048)
			(end 0.67945 0.3048)
			(stroke
				(width 0.1)
				(type default)
			)
			(layer "F.Fab")
		)
		(fp_line
			(start 0.67945 0.3048)
			(end 0.120396 0.3048)
			(stroke
				(width 0.1)
				(type default)
			)
			(layer "F.Fab")
		)
		(pad "1" smd circle
			(at -0.40005 0)
			(size 0 0)
			(layers "F.Cu" "F.Mask" "F.Paste")
			(net "P3V3_AUX")
		)
		(pad "2" smd circle
			(at 0.40005 0)
			(size 0 0)
			(layers "F.Cu" "F.Mask" "F.Paste")
			(net "GND")
		)
	)
	(footprint ""
		(layer "F.Cu")
		(at 308.4576 -21.1836)
		(property "Reference" "U341"
			(at 2.159 -0.11811 0)
			(unlocked yes)
			(layer "F.SilkS")
			(effects
				(font
					(size 0.7874 0.5842)
					(thickness 0.1524)
				)
				(justify left)
			)
		)
		(property "Value" ""
			(at 0 0 0)
			(layer "F.Fab")
			(effects
				(font
					(size 1.27 1.27)
				)
			)
		)
		(duplicate_pad_numbers_are_jumpers no)
		(fp_line
			(start -1.868424 -1.519936)
			(end -1.868424 1.519936)
			(stroke
				(width 0.1524)
				(type default)
			)
			(layer "F.SilkS")
		)
		(fp_line
			(start -1.868424 1.519936)
			(end 1.868424 1.519936)
			(stroke
				(width 0.1524)
				(type default)
			)
			(layer "F.SilkS")
		)
		(fp_line
			(start 1.868424 -1.519936)
			(end -1.868424 -1.519936)
			(stroke
				(width 0.1524)
				(type default)
			)
			(layer "F.SilkS")
		)
		(fp_line
			(start 1.868424 1.519936)
			(end 1.868424 -1.519936)
			(stroke
				(width 0.1524)
				(type default)
			)
			(layer "F.SilkS")
		)
		(fp_line
			(start -0.700024 -1.519936)
			(end -0.700024 1.519936)
			(stroke
				(width 0.1)
				(type default)
			)
			(layer "F.Fab")
		)
		(fp_line
			(start -0.700024 1.519936)
			(end 0.700024 1.519936)
			(stroke
				(width 0.1)
				(type default)
			)
			(layer "F.Fab")
		)
		(fp_line
			(start 0.700024 -1.519936)
			(end -0.700024 -1.519936)
			(stroke
				(width 0.1)
				(type default)
			)
			(layer "F.Fab")
		)
		(fp_line
			(start 0.700024 1.519936)
			(end 0.700024 -1.519936)
			(stroke
				(width 0.1)
				(type default)
			)
			(layer "F.Fab")
		)
		(pad "1" smd rect
			(at -1.18491 -0.94996 270)
			(size 0.6096 1.0668)
			(layers "F.Cu" "F.Mask" "F.Paste")
			(net "DSW_PWROK_P2V5_COMP")
		)
		(pad "2" smd rect
			(at -1.18491 0.94996 270)
			(size 0.6096 1.0668)
			(layers "F.Cu" "F.Mask" "F.Paste")
			(net "GND")
		)
		(pad "3" smd rect
			(at 1.18491 0 270)
			(size 0.6096 1.0668)
			(layers "F.Cu" "F.Mask" "F.Paste")
			(net "Net_8630")
		)
	)
	(footprint ""
		(layer "F.Cu")
		(at 352.270314 -255.053846 90)
		(property "Reference" "C982"
			(at 0 0 90)
			(layer "F.SilkS")
			(hide yes)
			(effects
				(font
					(size 1.27 1.27)
				)
			)
		)
		(property "Value" ""
			(at 0 0 90)
			(layer "F.Fab")
			(effects
				(font
					(size 1.27 1.27)
				)
			)
		)
		(duplicate_pad_numbers_are_jumpers no)
		(fp_line
			(start 0.7874 -0.4064)
			(end 0.7874 0.4064)
			(stroke
				(width 0.1524)
				(type default)
			)
			(layer "F.SilkS")
		)
		(fp_line
			(start -0.7874 -0.4064)
			(end 0.7874 -0.4064)
			(stroke
				(width 0.1524)
				(type default)
			)
			(layer "F.SilkS")
		)
		(fp_line
			(start 0.7874 0.4064)
			(end -0.7874 0.4064)
			(stroke
				(width 0.1524)
				(type default)
			)
			(layer "F.SilkS")
		)
		(fp_line
			(start -0.7874 0.4064)
			(end -0.7874 -0.4064)
			(stroke
				(width 0.1524)
				(type default)
			)
			(layer "F.SilkS")
		)
		(fp_line
			(start -0.12065 -0.305054)
			(end -0.12065 -0.2794)
			(stroke
				(width 0.1)
				(type default)
			)
			(layer "F.Fab")
		)
		(fp_line
			(start -0.67945 -0.305054)
			(end -0.12065 -0.305054)
			(stroke
				(width 0.1)
				(type default)
			)
			(layer "F.Fab")
		)
		(fp_line
			(start 0.67945 -0.3048)
			(end 0.67945 0.3048)
			(stroke
				(width 0.1)
				(type default)
			)
			(layer "F.Fab")
		)
		(fp_line
			(start 0.12065 -0.3048)
			(end 0.67945 -0.3048)
			(stroke
				(width 0.1)
				(type default)
			)
			(layer "F.Fab")
		)
		(fp_line
			(start 0.12065 -0.2794)
			(end 0.12065 -0.3048)
			(stroke
				(width 0.1)
				(type default)
			)
			(layer "F.Fab")
		)
		(fp_line
			(start -0.12065 -0.2794)
			(end 0.12065 -0.2794)
			(stroke
				(width 0.1)
				(type default)
			)
			(layer "F.Fab")
		)
		(fp_line
			(start 0.120396 0.2794)
			(end -0.12065 0.2794)
			(stroke
				(width 0.1)
				(type default)
			)
			(layer "F.Fab")
		)
		(fp_line
			(start -0.12065 0.2794)
			(end -0.12065 0.3048)
			(stroke
				(width 0.1)
				(type default)
			)
			(layer "F.Fab")
		)
		(fp_line
			(start 0.67945 0.3048)
			(end 0.120396 0.3048)
			(stroke
				(width 0.1)
				(type default)
			)
			(layer "F.Fab")
		)
		(fp_line
			(start 0.120396 0.3048)
			(end 0.120396 0.2794)
			(stroke
				(width 0.1)
				(type default)
			)
			(layer "F.Fab")
		)
		(fp_line
			(start -0.12065 0.3048)
			(end -0.67945 0.3048)
			(stroke
				(width 0.1)
				(type default)
			)
			(layer "F.Fab")
		)
		(fp_line
			(start -0.67945 0.3048)
			(end -0.67945 -0.305054)
			(stroke
				(width 0.1)
				(type default)
			)
			(layer "F.Fab")
		)
		(pad "1" smd circle
			(at -0.40005 0 90)
			(size 0 0)
			(layers "F.Cu" "F.Mask" "F.Paste")
			(net "PVCCIN_CPU0")
		)
		(pad "2" smd circle
			(at 0.40005 0 90)
			(size 0 0)
			(layers "F.Cu" "F.Mask" "F.Paste")
			(net "GND")
		)
	)
	(footprint ""
		(layer "F.Cu")
		(at 201.00036 -119.344948 180)
		(property "Reference" "R735"
			(at 0 0 180)
			(layer "F.SilkS")
			(hide yes)
			(effects
				(font
					(size 1.27 1.27)
				)
			)
		)
		(property "Value" ""
			(at 0 0 180)
			(layer "F.Fab")
			(effects
				(font
					(size 1.27 1.27)
				)
			)
		)
		(duplicate_pad_numbers_are_jumpers no)
		(fp_line
			(start 0.7874 0.4064)
			(end -0.7874 0.4064)
			(stroke
				(width 0.1524)
				(type default)
			)
			(layer "F.SilkS")
		)
		(fp_line
			(start 0.7874 -0.4064)
			(end 0.7874 0.4064)
			(stroke
				(width 0.1524)
				(type default)
			)
			(layer "F.SilkS")
		)
		(fp_line
			(start -0.7874 0.4064)
			(end -0.7874 -0.4064)
			(stroke
				(width 0.1524)
				(type default)
			)
			(layer "F.SilkS")
		)
		(fp_line
			(start -0.7874 -0.4064)
			(end 0.7874 -0.4064)
			(stroke
				(width 0.1524)
				(type default)
			)
			(layer "F.SilkS")
		)
		(fp_line
			(start 0.67945 0.3048)
			(end 0.120396 0.3048)
			(stroke
				(width 0.1)
				(type default)
			)
			(layer "F.Fab")
		)
		(fp_line
			(start 0.67945 -0.3048)
			(end 0.67945 0.3048)
			(stroke
				(width 0.1)
				(type default)
			)
			(layer "F.Fab")
		)
		(fp_line
			(start 0.12065 -0.2794)
			(end 0.12065 -0.3048)
			(stroke
				(width 0.1)
				(type default)
			)
			(layer "F.Fab")
		)
		(fp_line
			(start 0.12065 -0.3048)
			(end 0.67945 -0.3048)
			(stroke
				(width 0.1)
				(type default)
			)
			(layer "F.Fab")
		)
		(fp_line
			(start 0.120396 0.3048)
			(end 0.120396 0.2794)
			(stroke
				(width 0.1)
				(type default)
			)
			(layer "F.Fab")
		)
		(fp_line
			(start 0.120396 0.2794)
			(end -0.12065 0.2794)
			(stroke
				(width 0.1)
				(type default)
			)
			(layer "F.Fab")
		)
		(fp_line
			(start -0.12065 0.3048)
			(end -0.67945 0.3048)
			(stroke
				(width 0.1)
				(type default)
			)
			(layer "F.Fab")
		)
		(fp_line
			(start -0.12065 0.2794)
			(end -0.12065 0.3048)
			(stroke
				(width 0.1)
				(type default)
			)
			(layer "F.Fab")
		)
		(fp_line
			(start -0.12065 -0.2794)
			(end 0.12065 -0.2794)
			(stroke
				(width 0.1)
				(type default)
			)
			(layer "F.Fab")
		)
		(fp_line
			(start -0.12065 -0.305054)
			(end -0.12065 -0.2794)
			(stroke
				(width 0.1)
				(type default)
			)
			(layer "F.Fab")
		)
		(fp_line
			(start -0.67945 0.3048)
			(end -0.67945 -0.305054)
			(stroke
				(width 0.1)
				(type default)
			)
			(layer "F.Fab")
		)
		(fp_line
			(start -0.67945 -0.305054)
			(end -0.12065 -0.305054)
			(stroke
				(width 0.1)
				(type default)
			)
			(layer "F.Fab")
		)
		(pad "1" smd circle
			(at -0.40005 0 180)
			(size 0 0)
			(layers "F.Cu" "F.Mask" "F.Paste")
			(net "P3V3_AUX")
		)
		(pad "2" smd circle
			(at 0.40005 0 180)
			(size 0 0)
			(layers "F.Cu" "F.Mask" "F.Paste")
			(net "FM_DIMM_12V_CPS_SX_N")
		)
	)
	(footprint ""
		(layer "F.Cu")
		(at 134.21106 -127.056388 180)
		(property "Reference" "R3158"
			(at 0 0 180)
			(layer "F.SilkS")
			(hide yes)
			(effects
				(font
					(size 1.27 1.27)
				)
			)
		)
		(property "Value" ""
			(at 0 0 180)
			(layer "F.Fab")
			(effects
				(font
					(size 1.27 1.27)
				)
			)
		)
		(duplicate_pad_numbers_are_jumpers no)
		(fp_line
			(start 0.7874 0.4064)
			(end -0.7874 0.4064)
			(stroke
				(width 0.1524)
				(type default)
			)
			(layer "F.SilkS")
		)
		(fp_line
			(start 0.7874 -0.4064)
			(end 0.7874 0.4064)
			(stroke
				(width 0.1524)
				(type default)
			)
			(layer "F.SilkS")
		)
		(fp_line
			(start -0.7874 0.4064)
			(end -0.7874 -0.4064)
			(stroke
				(width 0.1524)
				(type default)
			)
			(layer "F.SilkS")
		)
		(fp_line
			(start -0.7874 -0.4064)
			(end 0.7874 -0.4064)
			(stroke
				(width 0.1524)
				(type default)
			)
			(layer "F.SilkS")
		)
		(fp_line
			(start 0.67945 0.3048)
			(end 0.120396 0.3048)
			(stroke
				(width 0.1)
				(type default)
			)
			(layer "F.Fab")
		)
		(fp_line
			(start 0.67945 -0.3048)
			(end 0.67945 0.3048)
			(stroke
				(width 0.1)
				(type default)
			)
			(layer "F.Fab")
		)
		(fp_line
			(start 0.12065 -0.2794)
			(end 0.12065 -0.3048)
			(stroke
				(width 0.1)
				(type default)
			)
			(layer "F.Fab")
		)
		(fp_line
			(start 0.12065 -0.3048)
			(end 0.67945 -0.3048)
			(stroke
				(width 0.1)
				(type default)
			)
			(layer "F.Fab")
		)
		(fp_line
			(start 0.120396 0.3048)
			(end 0.120396 0.2794)
			(stroke
				(width 0.1)
				(type default)
			)
			(layer "F.Fab")
		)
		(fp_line
			(start 0.120396 0.2794)
			(end -0.12065 0.2794)
			(stroke
				(width 0.1)
				(type default)
			)
			(layer "F.Fab")
		)
		(fp_line
			(start -0.12065 0.3048)
			(end -0.67945 0.3048)
			(stroke
				(width 0.1)
				(type default)
			)
			(layer "F.Fab")
		)
		(fp_line
			(start -0.12065 0.2794)
			(end -0.12065 0.3048)
			(stroke
				(width 0.1)
				(type default)
			)
			(layer "F.Fab")
		)
		(fp_line
			(start -0.12065 -0.2794)
			(end 0.12065 -0.2794)
			(stroke
				(width 0.1)
				(type default)
			)
			(layer "F.Fab")
		)
		(fp_line
			(start -0.12065 -0.305054)
			(end -0.12065 -0.2794)
			(stroke
				(width 0.1)
				(type default)
			)
			(layer "F.Fab")
		)
		(fp_line
			(start -0.67945 0.3048)
			(end -0.67945 -0.305054)
			(stroke
				(width 0.1)
				(type default)
			)
			(layer "F.Fab")
		)
		(fp_line
			(start -0.67945 -0.305054)
			(end -0.12065 -0.305054)
			(stroke
				(width 0.1)
				(type default)
			)
			(layer "F.Fab")
		)
		(pad "1" smd circle
			(at -0.40005 0 180)
			(size 0 0)
			(layers "F.Cu" "F.Mask" "F.Paste")
			(net "FM_SMB_CPU1_ALERT")
		)
		(pad "2" smd circle
			(at 0.40005 0 180)
			(size 0 0)
			(layers "F.Cu" "F.Mask" "F.Paste")
			(net "FM_SMB_PEHPCPU1_PCIE_ALERT_N")
		)
	)
)
